FILE_TYPE = CONNECTIVITY;
{Allegro Design Entry HDL 17.2-2016 S081 (4005846) 1/11/2022}
"PAGE_NUMBER" = 66;
0"NC";
1"GND\g";
%"SOCKET4677_AZIF0045P001C01CS"
"25","(600,2750)","0","pure_quanta","I16";
;
PART_NUMBER"DGA^7000023"
PART_TYPE"SMLF"
MATERIAL"IO"
VALUE"SOCKET4677_AZIF0045-P001C01CS"
$LOCATION"U1"
CDS_LIB"pure_quanta"
NEEDS_NO_SIZE"TRUE"
CDS_LMAN_SYM_OUTLINE"-1050,1350,1050,-1350"
CDS_LOCATION"U1"
$SEC"25"
CDS_SEC"25";
"UPI3_TX_DP0"
$PN"EK85"0;
"UPI3_TX_DP1"
$PN"EM85"0;
"UPI3_TX_DP2"
$PN"EN86"0;
"UPI3_TX_DP3"
$PN"EP87"0;
"UPI3_TX_DP4"
$PN"EH87"0;
"UPI3_TX_DP5"
$PN"EL88"0;
"UPI3_TX_DP6"
$PN"DT81"0;
"UPI3_TX_DP7"
$PN"DU82"0;
"UPI3_TX_DP8"
$PN"DR80"0;
"UPI3_TX_DP9"
$PN"DP83"0;
"UPI3_TX_DP10"
$PN"DL82"0;
"UPI3_TX_DP11"
$PN"DN80"0;
"UPI3_TX_DP12"
$PN"DA76"0;
"UPI3_TX_DP13"
$PN"CV77"0;
"UPI3_TX_DP14"
$PN"CR76"0;
"UPI3_TX_DP15"
$PN"CU74"0;
"UPI3_TX_DP16"
$PN"CM77"0;
"UPI3_TX_DP17"
$PN"CJ78"0;
"UPI3_TX_DP18"
$PN"CL76"0;
"UPI3_TX_DP19"
$PN"CF77"0;
"UPI3_TX_DP20"
$PN"CH75"0;
"UPI3_TX_DP21"
$PN"CK75"0;
"UPI3_TX_DP22"
$PN"CW74"0;
"UPI3_TX_DP23"
$PN"CD73"0;
"UPI3_TX_DN0"
$PN"EH85"0;
"UPI3_TX_DN1"
$PN"EL84"0;
"UPI3_TX_DN2"
$PN"EP85"0;
"UPI3_TX_DN3"
$PN"EM87"0;
"UPI3_TX_DN4"
$PN"EJ86"0;
"UPI3_TX_DN5"
$PN"EK87"0;
"UPI3_TX_DN6"
$PN"DU80"0;
"UPI3_TX_DN7"
$PN"DR82"0;
"UPI3_TX_DN8"
$PN"DP79"0;
"UPI3_TX_DN9"
$PN"DN82"0;
"UPI3_TX_DN10"
$PN"DM81"0;
"UPI3_TX_DN11"
$PN"DL80"0;
"UPI3_TX_DN12"
$PN"CW76"0;
"UPI3_TX_DN13"
$PN"CU76"0;
"UPI3_TX_DN14"
$PN"CT75"0;
"UPI3_TX_DN15"
$PN"CR74"0;
"UPI3_TX_DN16"
$PN"CK77"0;
"UPI3_TX_DN17"
$PN"CH77"0;
"UPI3_TX_DN18"
$PN"CM75"0;
"UPI3_TX_DN19"
$PN"CG76"0;
"UPI3_TX_DN20"
$PN"CF75"0;
"UPI3_TX_DN21"
$PN"CJ74"0;
"UPI3_TX_DN22"
$PN"CV73"0;
"UPI3_TX_DN23"
$PN"CF73"0;
"UPI3_RX_DP0"
$PN"EL80"1;
"UPI3_RX_DP1"
$PN"ER82"1;
"UPI3_RX_DP2"
$PN"EN82"1;
"UPI3_RX_DP3"
$PN"EJ82"1;
"UPI3_RX_DP4"
$PN"EE82"1;
"UPI3_RX_DP5"
$PN"EF83"1;
"UPI3_RX_DP6"
$PN"ED81"1;
"UPI3_RX_DP7"
$PN"DY83"1;
"UPI3_RX_DP8"
$PN"EB81"1;
"UPI3_RX_DP9"
$PN"DL78"1;
"UPI3_RX_DP10"
$PN"DH79"1;
"UPI3_RX_DP11"
$PN"DG82"1;
"UPI3_RX_DP12"
$PN"DH83"1;
"UPI3_RX_DP13"
$PN"DF81"1;
"UPI3_RX_DP14"
$PN"DB83"1;
"UPI3_RX_DP15"
$PN"DD81"1;
"UPI3_RX_DP16"
$PN"DE78"1;
"UPI3_RX_DP17"
$PN"CW82"1;
"UPI3_RX_DP18"
$PN"CT83"1;
"UPI3_RX_DP19"
$PN"CV81"1;
"UPI3_RX_DP20"
$PN"CN82"1;
"UPI3_RX_DP21"
$PN"CR80"1;
"UPI3_RX_DP22"
$PN"CU80"1;
"UPI3_RX_DP23"
$PN"DB79"1;
"UPI3_RX_DN0"
$PN"EJ80"1;
"UPI3_RX_DN1"
$PN"EP81"1;
"UPI3_RX_DN2"
$PN"EL82"1;
"UPI3_RX_DN3"
$PN"EK81"1;
"UPI3_RX_DN4"
$PN"EF81"1;
"UPI3_RX_DN5"
$PN"ED83"1;
"UPI3_RX_DN6"
$PN"EC80"1;
"UPI3_RX_DN7"
$PN"EA82"1;
"UPI3_RX_DN8"
$PN"DY81"1;
"UPI3_RX_DN9"
$PN"DJ78"1;
"UPI3_RX_DN10"
$PN"DG78"1;
"UPI3_RX_DN11"
$PN"DH81"1;
"UPI3_RX_DN12"
$PN"DF83"1;
"UPI3_RX_DN13"
$PN"DE80"1;
"UPI3_RX_DN14"
$PN"DC82"1;
"UPI3_RX_DN15"
$PN"DB81"1;
"UPI3_RX_DN16"
$PN"DF77"1;
"UPI3_RX_DN17"
$PN"CU82"1;
"UPI3_RX_DN18"
$PN"CR82"1;
"UPI3_RX_DN19"
$PN"CW80"1;
"UPI3_RX_DN20"
$PN"CP81"1;
"UPI3_RX_DN21"
$PN"CN80"1;
"UPI3_RX_DN22"
$PN"CT79"1;
"UPI3_RX_DN23"
$PN"DA78"1;
%"UNIVERSAL_GND"
"1","(-900,1225)","0","logical_power","I17";
;
CDS_LIB"logical_power"
HDL_POWER"GND";
"A"1;
END.
